(kicad_pcb
	(version 20260206)
	(generator "pcbnew")
	(generator_version "10.0")
	(general
		(thickness 1.6)
		(legacy_teardrops no)
	)
	(paper "A4")
	(title_block
		(title "peb — Lightning_PEB_BRD.brd")
		(comment 1 "Lightning (Wiwynn / Facebook NVMe JBOF) / footprints 2506-2513 of 2563")
	)
	(layers
		(0 "F.Cu" signal "TOP")
		(4 "In1.Cu" signal "L2GND")
		(6 "In2.Cu" signal "L3")
		(8 "In3.Cu" signal "L4VCC")
		(10 "In4.Cu" signal "L5VCC")
		(12 "In5.Cu" signal "L6")
		(14 "In6.Cu" signal "L7GND")
		(2 "B.Cu" signal "BOTTOM")
		(9 "F.Adhes" user "F.Adhesive")
		(11 "B.Adhes" user "B.Adhesive")
		(13 "F.Paste" user "Package Geometry/Pastemask Top")
		(15 "B.Paste" user "Package Geometry/Pastemask Bottom")
		(5 "F.SilkS" user "Ref Des/Silkscreen Top")
		(7 "B.SilkS" user "Ref Des/Silkscreen Bottom")
		(1 "F.Mask" user "Board Geometry/Soldermask Top")
		(3 "B.Mask" user "Board Geometry/Soldermask Bottom")
		(17 "Dwgs.User" user "User.Drawings")
		(19 "Cmts.User" user "User.Comments")
		(21 "Eco1.User" user "User.Eco1")
		(23 "Eco2.User" user "User.Eco2")
		(25 "Edge.Cuts" user "Board Geometry/Outline")
		(27 "Margin" user)
		(31 "F.CrtYd" user "Package Geometry/Place Bound Top")
		(29 "B.CrtYd" user "Package Geometry/Place Bound Bottom")
		(35 "F.Fab" user "Ref Des/Assembly Top")
		(33 "B.Fab" user "Ref Des/Assembly Bottom")
	)
	(footprint ""
		(layer "B.Cu")
		(at 254.068072 -41.012872 90)
		(property "Reference" "C589"
			(at 0 0 90)
			(layer "B.SilkS")
			(hide yes)
			(effects
				(font
					(size 1.27 1.27)
				)
				(justify mirror)
			)
		)
		(property "Value" "SCD1U16V1KX-1-GP"
			(at 2.8321 -1.7399 90)
			(unlocked yes)
			(layer "B.Fab")
			(hide yes)
			(effects
				(font
					(size 1.016 1.016)
					(thickness 0.1524)
				)
				(justify mirror)
			)
		)
		(property "Device Type" "C0201H13"
			(at 2.8321 -3.2639 90)
			(unlocked yes)
			(layer "B.Fab")
			(hide yes)
			(effects
				(font
					(size 1.016 1.016)
					(thickness 0.1524)
				)
				(justify mirror)
			)
		)
		(duplicate_pad_numbers_are_jumpers no)
		(fp_rect
			(start 0.2794 0.6477)
			(end -0.2794 -0.6477)
			(stroke
				(width 0)
				(type default)
			)
			(fill no)
			(layer "B.CrtYd")
		)
		(fp_rect
			(start 0.2794 0.6477)
			(end -0.2794 -0.6477)
			(stroke
				(width 0)
				(type default)
			)
			(fill no)
			(layer "B.Fab")
		)
		(pad "1" smd custom
			(at 0 -0.2794 270)
			(size 0.0762 0.0762)
			(layers "B.Cu" "B.Mask" "B.Paste")
			(net "DUT_AVD_PCIE")
			(options
				(clearance outline)
				(anchor circle)
			)
			(primitives
				(gr_poly
					(pts
						(arc
							(start 0.1524 0.127)
							(mid 0.137521 0.162921)
							(end 0.1016 0.1778)
						)
						(arc
							(start -0.1016 0.1778)
							(mid -0.137521 0.162921)
							(end -0.1524 0.127)
						)
						(arc
							(start -0.1524 -0.127)
							(mid -0.137521 -0.162921)
							(end -0.1016 -0.1778)
						)
						(arc
							(start 0.1016 -0.1778)
							(mid 0.137521 -0.162921)
							(end 0.1524 -0.127)
						)
					)
					(width 0)
					(fill yes)
				)
			)
		)
		(pad "2" smd custom
			(at 0 0.2794 270)
			(size 0.0762 0.0762)
			(layers "B.Cu" "B.Mask" "B.Paste")
			(net "GND")
			(options
				(clearance outline)
				(anchor circle)
			)
			(primitives
				(gr_poly
					(pts
						(arc
							(start 0.1524 0.127)
							(mid 0.137521 0.162921)
							(end 0.1016 0.1778)
						)
						(arc
							(start -0.1016 0.1778)
							(mid -0.137521 0.162921)
							(end -0.1524 0.127)
						)
						(arc
							(start -0.1524 -0.127)
							(mid -0.137521 -0.162921)
							(end -0.1016 -0.1778)
						)
						(arc
							(start 0.1016 -0.1778)
							(mid 0.137521 -0.162921)
							(end 0.1524 -0.127)
						)
					)
					(width 0)
					(fill yes)
				)
			)
		)
	)
	(footprint ""
		(layer "B.Cu")
		(at 242.3414 -35.0012 -90)
		(property "Reference" "C474"
			(at 0 0 90)
			(layer "B.SilkS")
			(hide yes)
			(effects
				(font
					(size 1.27 1.27)
				)
				(justify mirror)
			)
		)
		(property "Value" "SCD1U16V1KX-1-GP"
			(at 2.8321 -1.7399 270)
			(unlocked yes)
			(layer "B.Fab")
			(hide yes)
			(effects
				(font
					(size 1.016 1.016)
					(thickness 0.1524)
				)
				(justify mirror)
			)
		)
		(property "Device Type" "C0201H13"
			(at 2.8321 -3.2639 270)
			(unlocked yes)
			(layer "B.Fab")
			(hide yes)
			(effects
				(font
					(size 1.016 1.016)
					(thickness 0.1524)
				)
				(justify mirror)
			)
		)
		(duplicate_pad_numbers_are_jumpers no)
		(fp_rect
			(start 0.2794 0.6477)
			(end -0.2794 -0.6477)
			(stroke
				(width 0)
				(type default)
			)
			(fill no)
			(layer "B.CrtYd")
		)
		(fp_rect
			(start 0.2794 0.6477)
			(end -0.2794 -0.6477)
			(stroke
				(width 0)
				(type default)
			)
			(fill no)
			(layer "B.Fab")
		)
		(pad "1" smd custom
			(at 0 -0.2794 90)
			(size 0.0762 0.0762)
			(layers "B.Cu" "B.Mask" "B.Paste")
			(net "DUT_VDDO")
			(options
				(clearance outline)
				(anchor circle)
			)
			(primitives
				(gr_poly
					(pts
						(arc
							(start 0.1524 0.127)
							(mid 0.137521 0.162921)
							(end 0.1016 0.1778)
						)
						(arc
							(start -0.1016 0.1778)
							(mid -0.137521 0.162921)
							(end -0.1524 0.127)
						)
						(arc
							(start -0.1524 -0.127)
							(mid -0.137521 -0.162921)
							(end -0.1016 -0.1778)
						)
						(arc
							(start 0.1016 -0.1778)
							(mid 0.137521 -0.162921)
							(end 0.1524 -0.127)
						)
					)
					(width 0)
					(fill yes)
				)
			)
		)
		(pad "2" smd custom
			(at 0 0.2794 90)
			(size 0.0762 0.0762)
			(layers "B.Cu" "B.Mask" "B.Paste")
			(net "GND")
			(options
				(clearance outline)
				(anchor circle)
			)
			(primitives
				(gr_poly
					(pts
						(arc
							(start 0.1524 0.127)
							(mid 0.137521 0.162921)
							(end 0.1016 0.1778)
						)
						(arc
							(start -0.1016 0.1778)
							(mid -0.137521 0.162921)
							(end -0.1524 0.127)
						)
						(arc
							(start -0.1524 -0.127)
							(mid -0.137521 -0.162921)
							(end -0.1016 -0.1778)
						)
						(arc
							(start 0.1016 -0.1778)
							(mid 0.137521 -0.162921)
							(end 0.1524 -0.127)
						)
					)
					(width 0)
					(fill yes)
				)
			)
		)
	)
	(footprint ""
		(layer "B.Cu")
		(at 237.1598 -51.9938 -90)
		(property "Reference" "C32"
			(at 0 0 90)
			(layer "B.SilkS")
			(hide yes)
			(effects
				(font
					(size 1.27 1.27)
				)
				(justify mirror)
			)
		)
		(property "Value" "SCD1U16V1KX-1-GP"
			(at 2.8321 -1.7399 270)
			(unlocked yes)
			(layer "B.Fab")
			(hide yes)
			(effects
				(font
					(size 1.016 1.016)
					(thickness 0.1524)
				)
				(justify mirror)
			)
		)
		(property "Device Type" "C0201H13"
			(at 2.8321 -3.2639 270)
			(unlocked yes)
			(layer "B.Fab")
			(hide yes)
			(effects
				(font
					(size 1.016 1.016)
					(thickness 0.1524)
				)
				(justify mirror)
			)
		)
		(duplicate_pad_numbers_are_jumpers no)
		(fp_rect
			(start 0.2794 0.6477)
			(end -0.2794 -0.6477)
			(stroke
				(width 0)
				(type default)
			)
			(fill no)
			(layer "B.CrtYd")
		)
		(fp_rect
			(start 0.2794 0.6477)
			(end -0.2794 -0.6477)
			(stroke
				(width 0)
				(type default)
			)
			(fill no)
			(layer "B.Fab")
		)
		(pad "1" smd custom
			(at 0 -0.2794 90)
			(size 0.0762 0.0762)
			(layers "B.Cu" "B.Mask" "B.Paste")
			(net "DUT_VDD")
			(options
				(clearance outline)
				(anchor circle)
			)
			(primitives
				(gr_poly
					(pts
						(arc
							(start 0.1524 0.127)
							(mid 0.137521 0.162921)
							(end 0.1016 0.1778)
						)
						(arc
							(start -0.1016 0.1778)
							(mid -0.137521 0.162921)
							(end -0.1524 0.127)
						)
						(arc
							(start -0.1524 -0.127)
							(mid -0.137521 -0.162921)
							(end -0.1016 -0.1778)
						)
						(arc
							(start 0.1016 -0.1778)
							(mid 0.137521 -0.162921)
							(end 0.1524 -0.127)
						)
					)
					(width 0)
					(fill yes)
				)
			)
		)
		(pad "2" smd custom
			(at 0 0.2794 90)
			(size 0.0762 0.0762)
			(layers "B.Cu" "B.Mask" "B.Paste")
			(net "GND")
			(options
				(clearance outline)
				(anchor circle)
			)
			(primitives
				(gr_poly
					(pts
						(arc
							(start 0.1524 0.127)
							(mid 0.137521 0.162921)
							(end 0.1016 0.1778)
						)
						(arc
							(start -0.1016 0.1778)
							(mid -0.137521 0.162921)
							(end -0.1524 0.127)
						)
						(arc
							(start -0.1524 -0.127)
							(mid -0.137521 -0.162921)
							(end -0.1016 -0.1778)
						)
						(arc
							(start 0.1016 -0.1778)
							(mid 0.137521 -0.162921)
							(end 0.1524 -0.127)
						)
					)
					(width 0)
					(fill yes)
				)
			)
		)
	)
	(footprint ""
		(layer "B.Cu")
		(at 16.149828 -74.982578 90)
		(property "Reference" "C636"
			(at 0 0 90)
			(layer "B.SilkS")
			(hide yes)
			(effects
				(font
					(size 1.27 1.27)
				)
				(justify mirror)
			)
		)
		(property "Value" "SCD1U16V2KX-3GP"
			(at -1.1811 -2.7051 90)
			(unlocked yes)
			(layer "B.Fab")
			(hide yes)
			(effects
				(font
					(size 1.016 1.016)
					(thickness 0.1524)
				)
				(justify mirror)
			)
		)
		(property "Device Type" "C402H22"
			(at -1.1811 -4.2291 90)
			(unlocked yes)
			(layer "B.Fab")
			(hide yes)
			(effects
				(font
					(size 1.016 1.016)
					(thickness 0.1524)
				)
				(justify mirror)
			)
		)
		(duplicate_pad_numbers_are_jumpers no)
		(fp_rect
			(start 0.4318 0.9525)
			(end -0.4318 -0.9525)
			(stroke
				(width 0)
				(type default)
			)
			(fill no)
			(layer "B.CrtYd")
		)
		(fp_rect
			(start 0.4318 0.9525)
			(end -0.4318 -0.9525)
			(stroke
				(width 0)
				(type default)
			)
			(fill no)
			(layer "B.Fab")
		)
		(pad "1" smd custom
			(at 0 -0.4445 270)
			(size 0.1524 0.1524)
			(layers "B.Cu" "B.Mask" "B.Paste")
			(net "P0V9_I210")
			(options
				(clearance outline)
				(anchor circle)
			)
			(primitives
				(gr_poly
					(pts
						(arc
							(start 0.3048 0.2032)
							(mid 0.275042 0.275042)
							(end 0.2032 0.3048)
						)
						(arc
							(start -0.2032 0.3048)
							(mid -0.275042 0.275042)
							(end -0.3048 0.2032)
						)
						(arc
							(start -0.3048 -0.2032)
							(mid -0.275042 -0.275042)
							(end -0.2032 -0.3048)
						)
						(arc
							(start 0.2032 -0.3048)
							(mid 0.275042 -0.275042)
							(end 0.3048 -0.2032)
						)
					)
					(width 0)
					(fill yes)
				)
			)
		)
		(pad "2" smd custom
			(at 0 0.4445 270)
			(size 0.1524 0.1524)
			(layers "B.Cu" "B.Mask" "B.Paste")
			(net "GND")
			(options
				(clearance outline)
				(anchor circle)
			)
			(primitives
				(gr_poly
					(pts
						(arc
							(start 0.3048 0.2032)
							(mid 0.275042 0.275042)
							(end 0.2032 0.3048)
						)
						(arc
							(start -0.2032 0.3048)
							(mid -0.275042 0.275042)
							(end -0.3048 0.2032)
						)
						(arc
							(start -0.3048 -0.2032)
							(mid -0.275042 -0.275042)
							(end -0.2032 -0.3048)
						)
						(arc
							(start 0.2032 -0.3048)
							(mid 0.275042 -0.275042)
							(end 0.3048 -0.2032)
						)
					)
					(width 0)
					(fill yes)
				)
			)
		)
	)
	(footprint ""
		(layer "B.Cu")
		(at 243.1288 -47.032672 90)
		(property "Reference" "C462"
			(at 0 0 90)
			(layer "B.SilkS")
			(hide yes)
			(effects
				(font
					(size 1.27 1.27)
				)
				(justify mirror)
			)
		)
		(property "Value" "SCD1U16V1KX-1-GP"
			(at 2.8321 -1.7399 90)
			(unlocked yes)
			(layer "B.Fab")
			(hide yes)
			(effects
				(font
					(size 1.016 1.016)
					(thickness 0.1524)
				)
				(justify mirror)
			)
		)
		(property "Device Type" "C0201H13"
			(at 2.8321 -3.2639 90)
			(unlocked yes)
			(layer "B.Fab")
			(hide yes)
			(effects
				(font
					(size 1.016 1.016)
					(thickness 0.1524)
				)
				(justify mirror)
			)
		)
		(duplicate_pad_numbers_are_jumpers no)
		(fp_rect
			(start 0.2794 0.6477)
			(end -0.2794 -0.6477)
			(stroke
				(width 0)
				(type default)
			)
			(fill no)
			(layer "B.CrtYd")
		)
		(fp_rect
			(start 0.2794 0.6477)
			(end -0.2794 -0.6477)
			(stroke
				(width 0)
				(type default)
			)
			(fill no)
			(layer "B.Fab")
		)
		(pad "1" smd custom
			(at 0 -0.2794 270)
			(size 0.0762 0.0762)
			(layers "B.Cu" "B.Mask" "B.Paste")
			(net "DUT_VDD")
			(options
				(clearance outline)
				(anchor circle)
			)
			(primitives
				(gr_poly
					(pts
						(arc
							(start 0.1524 0.127)
							(mid 0.137521 0.162921)
							(end 0.1016 0.1778)
						)
						(arc
							(start -0.1016 0.1778)
							(mid -0.137521 0.162921)
							(end -0.1524 0.127)
						)
						(arc
							(start -0.1524 -0.127)
							(mid -0.137521 -0.162921)
							(end -0.1016 -0.1778)
						)
						(arc
							(start 0.1016 -0.1778)
							(mid 0.137521 -0.162921)
							(end 0.1524 -0.127)
						)
					)
					(width 0)
					(fill yes)
				)
			)
		)
		(pad "2" smd custom
			(at 0 0.2794 270)
			(size 0.0762 0.0762)
			(layers "B.Cu" "B.Mask" "B.Paste")
			(net "GND")
			(options
				(clearance outline)
				(anchor circle)
			)
			(primitives
				(gr_poly
					(pts
						(arc
							(start 0.1524 0.127)
							(mid 0.137521 0.162921)
							(end 0.1016 0.1778)
						)
						(arc
							(start -0.1016 0.1778)
							(mid -0.137521 0.162921)
							(end -0.1524 0.127)
						)
						(arc
							(start -0.1524 -0.127)
							(mid -0.137521 -0.162921)
							(end -0.1016 -0.1778)
						)
						(arc
							(start 0.1016 -0.1778)
							(mid 0.137521 -0.162921)
							(end 0.1524 -0.127)
						)
					)
					(width 0)
					(fill yes)
				)
			)
		)
	)
	(footprint ""
		(layer "B.Cu")
		(at 219.120212 -194.038474)
		(property "Reference" "C416"
			(at 0 0 0)
			(layer "B.SilkS")
			(hide yes)
			(effects
				(font
					(size 1.27 1.27)
				)
				(justify mirror)
			)
		)
		(property "Value" "SCD1U25V2KX-2-GP"
			(at -1.1811 -2.7051 0)
			(unlocked yes)
			(layer "B.Fab")
			(hide yes)
			(effects
				(font
					(size 1.016 1.016)
					(thickness 0.1524)
				)
				(justify mirror)
			)
		)
		(property "Device Type" "C402H22"
			(at -1.1811 -4.2291 0)
			(unlocked yes)
			(layer "B.Fab")
			(hide yes)
			(effects
				(font
					(size 1.016 1.016)
					(thickness 0.1524)
				)
				(justify mirror)
			)
		)
		(duplicate_pad_numbers_are_jumpers no)
		(fp_rect
			(start 0.4318 0.9525)
			(end -0.4318 -0.9525)
			(stroke
				(width 0)
				(type default)
			)
			(fill no)
			(layer "B.CrtYd")
		)
		(fp_rect
			(start 0.4318 0.9525)
			(end -0.4318 -0.9525)
			(stroke
				(width 0)
				(type default)
			)
			(fill no)
			(layer "B.Fab")
		)
		(pad "1" smd custom
			(at 0 -0.4445 180)
			(size 0.1524 0.1524)
			(layers "B.Cu" "B.Mask" "B.Paste")
			(net "P3V3_STBY")
			(options
				(clearance outline)
				(anchor circle)
			)
			(primitives
				(gr_poly
					(pts
						(arc
							(start 0.3048 0.2032)
							(mid 0.275042 0.275042)
							(end 0.2032 0.3048)
						)
						(arc
							(start -0.2032 0.3048)
							(mid -0.275042 0.275042)
							(end -0.3048 0.2032)
						)
						(arc
							(start -0.3048 -0.2032)
							(mid -0.275042 -0.275042)
							(end -0.2032 -0.3048)
						)
						(arc
							(start 0.2032 -0.3048)
							(mid 0.275042 -0.275042)
							(end 0.3048 -0.2032)
						)
					)
					(width 0)
					(fill yes)
				)
			)
		)
		(pad "2" smd custom
			(at 0 0.4445 180)
			(size 0.1524 0.1524)
			(layers "B.Cu" "B.Mask" "B.Paste")
			(net "GND")
			(options
				(clearance outline)
				(anchor circle)
			)
			(primitives
				(gr_poly
					(pts
						(arc
							(start 0.3048 0.2032)
							(mid 0.275042 0.275042)
							(end 0.2032 0.3048)
						)
						(arc
							(start -0.2032 0.3048)
							(mid -0.275042 0.275042)
							(end -0.3048 0.2032)
						)
						(arc
							(start -0.3048 -0.2032)
							(mid -0.275042 -0.275042)
							(end -0.2032 -0.3048)
						)
						(arc
							(start 0.2032 -0.3048)
							(mid 0.275042 -0.275042)
							(end 0.3048 -0.2032)
						)
					)
					(width 0)
					(fill yes)
				)
			)
		)
	)
	(footprint ""
		(layer "B.Cu")
		(at 227.6856 -34.004758 -90)
		(property "Reference" "C566"
			(at 0 0 90)
			(layer "B.SilkS")
			(hide yes)
			(effects
				(font
					(size 1.27 1.27)
				)
				(justify mirror)
			)
		)
		(property "Value" "SCD1U16V1KX-1-GP"
			(at 2.8321 -1.7399 270)
			(unlocked yes)
			(layer "B.Fab")
			(hide yes)
			(effects
				(font
					(size 1.016 1.016)
					(thickness 0.1524)
				)
				(justify mirror)
			)
		)
		(property "Device Type" "C0201H13"
			(at 2.8321 -3.2639 270)
			(unlocked yes)
			(layer "B.Fab")
			(hide yes)
			(effects
				(font
					(size 1.016 1.016)
					(thickness 0.1524)
				)
				(justify mirror)
			)
		)
		(duplicate_pad_numbers_are_jumpers no)
		(fp_rect
			(start 0.2794 0.6477)
			(end -0.2794 -0.6477)
			(stroke
				(width 0)
				(type default)
			)
			(fill no)
			(layer "B.CrtYd")
		)
		(fp_rect
			(start 0.2794 0.6477)
			(end -0.2794 -0.6477)
			(stroke
				(width 0)
				(type default)
			)
			(fill no)
			(layer "B.Fab")
		)
		(pad "1" smd custom
			(at 0 -0.2794 90)
			(size 0.0762 0.0762)
			(layers "B.Cu" "B.Mask" "B.Paste")
			(net "DUT_AVD_PCIE")
			(options
				(clearance outline)
				(anchor circle)
			)
			(primitives
				(gr_poly
					(pts
						(arc
							(start 0.1524 0.127)
							(mid 0.137521 0.162921)
							(end 0.1016 0.1778)
						)
						(arc
							(start -0.1016 0.1778)
							(mid -0.137521 0.162921)
							(end -0.1524 0.127)
						)
						(arc
							(start -0.1524 -0.127)
							(mid -0.137521 -0.162921)
							(end -0.1016 -0.1778)
						)
						(arc
							(start 0.1016 -0.1778)
							(mid 0.137521 -0.162921)
							(end 0.1524 -0.127)
						)
					)
					(width 0)
					(fill yes)
				)
			)
		)
		(pad "2" smd custom
			(at 0 0.2794 90)
			(size 0.0762 0.0762)
			(layers "B.Cu" "B.Mask" "B.Paste")
			(net "GND")
			(options
				(clearance outline)
				(anchor circle)
			)
			(primitives
				(gr_poly
					(pts
						(arc
							(start 0.1524 0.127)
							(mid 0.137521 0.162921)
							(end 0.1016 0.1778)
						)
						(arc
							(start -0.1016 0.1778)
							(mid -0.137521 0.162921)
							(end -0.1524 0.127)
						)
						(arc
							(start -0.1524 -0.127)
							(mid -0.137521 -0.162921)
							(end -0.1016 -0.1778)
						)
						(arc
							(start 0.1016 -0.1778)
							(mid 0.137521 -0.162921)
							(end 0.1524 -0.127)
						)
					)
					(width 0)
					(fill yes)
				)
			)
		)
	)
	(footprint ""
		(layer "B.Cu")
		(at 331.756512 -172.432218 180)
		(property "Reference" "R576"
			(at 0 0 0)
			(layer "B.SilkS")
			(hide yes)
			(effects
				(font
					(size 1.27 1.27)
				)
				(justify mirror)
			)
		)
		(property "Value" "10KR2F-2-GP"
			(at -0.064008 -3.993896 180)
			(unlocked yes)
			(layer "B.Fab")
			(hide yes)
			(effects
				(font
					(size 1.016 1.016)
					(thickness 0.1524)
				)
				(justify mirror)
			)
		)
		(property "Device Type" "R402H16"
			(at -0.064008 -5.517896 180)
			(unlocked yes)
			(layer "B.Fab")
			(hide yes)
			(effects
				(font
					(size 1.016 1.016)
					(thickness 0.1524)
				)
				(justify mirror)
			)
		)
		(duplicate_pad_numbers_are_jumpers no)
		(fp_line
			(start 0.508 -0.9398)
			(end 0.508 0.9398)
			(stroke
				(width 0.1524)
				(type default)
			)
			(layer "B.SilkS")
		)
		(fp_line
			(start -0.508 -0.9398)
			(end 0.508 -0.9398)
			(stroke
				(width 0.1524)
				(type default)
			)
			(layer "B.SilkS")
		)
		(fp_rect
			(start 0.508 0.9398)
			(end -0.508 -0.9398)
			(stroke
				(width 0)
				(type default)
			)
			(fill no)
			(layer "B.CrtYd")
		)
		(fp_rect
			(start 0.508 0.9398)
			(end -0.508 -0.9398)
			(stroke
				(width 0)
				(type default)
			)
			(fill no)
			(layer "B.Fab")
		)
		(pad "1" smd custom
			(at 0 -0.4445)
			(size 0.1397 0.1397)
			(layers "B.Cu" "B.Mask" "B.Paste")
			(net "P3V3_STBY")
			(options
				(clearance outline)
				(anchor circle)
			)
			(primitives
				(gr_poly
					(pts
						(arc
							(start -0.1778 0.2794)
							(mid -0.249642 0.249642)
							(end -0.2794 0.1778)
						)
						(arc
							(start -0.2794 -0.1778)
							(mid -0.249642 -0.249642)
							(end -0.1778 -0.2794)
						)
						(arc
							(start 0.1778 -0.2794)
							(mid 0.249642 -0.249642)
							(end 0.2794 -0.1778)
						)
						(arc
							(start 0.2794 0.1778)
							(mid 0.249642 0.249642)
							(end 0.1778 0.2794)
						)
					)
					(width 0)
					(fill yes)
				)
			)
		)
		(pad "2" smd custom
			(at 0 0.4445)
			(size 0.1397 0.1397)
			(layers "B.Cu" "B.Mask" "B.Paste")
			(net "IOEXP4_AD2")
			(options
				(clearance outline)
				(anchor circle)
			)
			(primitives
				(gr_poly
					(pts
						(arc
							(start -0.1778 0.2794)
							(mid -0.249642 0.249642)
							(end -0.2794 0.1778)
						)
						(arc
							(start -0.2794 -0.1778)
							(mid -0.249642 -0.249642)
							(end -0.1778 -0.2794)
						)
						(arc
							(start 0.1778 -0.2794)
							(mid 0.249642 -0.249642)
							(end 0.2794 -0.1778)
						)
						(arc
							(start 0.2794 0.1778)
							(mid 0.249642 0.249642)
							(end 0.1778 0.2794)
						)
					)
					(width 0)
					(fill yes)
				)
			)
		)
	)
)
